FILE_TYPE=LIBRARY_PARTS;
TIME=' Created/Modified on Fri Feb 08 08:35:19 2002' ;
primitive 'CAP_A','CAP_A_0402';
  pin
    'A':
      PIN_NUMBER='(1)';
      PINUSE='UNSPEC';
      NO_LOAD_CHECK='BOTH';
      NO_IO_CHECK='BOTH';
      ALLOW_CONNECT='TRUE';
      PIN_GROUP='1';
    'B':
      PIN_NUMBER='(2)';
      PINUSE='UNSPEC';
      NO_LOAD_CHECK='BOTH';
      NO_IO_CHECK='BOTH';
      ALLOW_CONNECT='TRUE';
      PIN_GROUP='1';
  end_pin;
  body
    PART_NAME='CAP_A';
    PHYS_DES_PREFIX='C';
  end_body;
end_primitive;
END.
